(kicad_pcb
	(version 20241229)
	(generator "pcbnew")
	(generator_version "9.0")
	(general
		(thickness 1.711)
		(legacy_teardrops no)
	)
	(paper "A4")
	(title_block
		(title "Antmicro Baseboard for Jetson AGX Thor")
		(date "2026-02-18")
		(rev "1.1.0")
		(company "Antmicro Ltd")
		(comment 1 "www.antmicro.com")
		(comment 9 "footprints 450-453 of 1170")
	)
	(layers
		(0 "F.Cu" signal)
		(4 "In1.Cu" signal)
		(6 "In2.Cu" signal)
		(8 "In3.Cu" signal)
		(10 "In4.Cu" jumper)
		(12 "In5.Cu" signal)
		(14 "In6.Cu" signal)
		(16 "In7.Cu" signal)
		(18 "In8.Cu" signal)
		(2 "B.Cu" signal)
		(9 "F.Adhes" user "F.Adhesive")
		(11 "B.Adhes" user "B.Adhesive")
		(13 "F.Paste" user)
		(15 "B.Paste" user)
		(5 "F.SilkS" user "F.Silkscreen")
		(7 "B.SilkS" user "B.Silkscreen")
		(1 "F.Mask" user)
		(3 "B.Mask" user)
		(17 "Dwgs.User" user "User.Drawings")
		(19 "Cmts.User" user "User.Comments")
		(21 "Eco1.User" user "User.Eco1")
		(23 "Eco2.User" user "User.Eco2")
		(25 "Edge.Cuts" user)
		(27 "Margin" user)
		(31 "F.CrtYd" user "F.Courtyard")
		(29 "B.CrtYd" user "B.Courtyard")
		(35 "F.Fab" user)
		(33 "B.Fab" user)
	)
	(footprint "antmicro-footprints:C_0402_1005Metric"
		(layer "F.Cu")
		(at 218.695 125.675 180)
		(descr "Capacitor SMD 0402")
		(tags "capacitor SMD 0402")
		(property "Reference" "C103"
			(at 0.835 0.365 0)
			(layer "F.SilkS")
			(effects
				(font
					(size 0.7 0.7)
					(thickness 0.15)
				)
				(justify right top)
			)
		)
		(property "Value" "C_100n_0402"
			(at -1.022927 2.155213 0)
			(layer "F.Fab")
			(effects
				(font
					(size 0.7 0.7)
					(thickness 0.15)
				)
				(justify right top)
			)
		)
		(property "Datasheet" "https://www.murata.com/products/productdetail?partno=GRM155R61H104KE14%23"
			(at 0 0 0)
			(layer "F.Fab")
			(hide yes)
			(effects
				(font
					(size 1.27 1.27)
					(thickness 0.15)
				)
			)
		)
		(property "Description" "SMD Multilayer Ceramic Capacitor, 0.1 µF, 50 V, 0402 [1005 Metric], ± 10%, X5R, GRM Series"
			(at 0 0 0)
			(layer "F.Fab")
			(hide yes)
			(effects
				(font
					(size 1.27 1.27)
					(thickness 0.15)
				)
			)
		)
		(property "Manufacturer" "Murata"
			(at 0 0 180)
			(unlocked yes)
			(layer "F.Fab")
			(hide yes)
			(effects
				(font
					(size 1 1)
					(thickness 0.15)
				)
			)
		)
		(property "MPN" "GRM155R61H104KE14D"
			(at 0 0 180)
			(unlocked yes)
			(layer "F.Fab")
			(hide yes)
			(effects
				(font
					(size 1 1)
					(thickness 0.15)
				)
			)
		)
		(property "Val" "100n"
			(at 0 0 180)
			(unlocked yes)
			(layer "F.Fab")
			(hide yes)
			(effects
				(font
					(size 1 1)
					(thickness 0.15)
				)
			)
		)
		(property "License" "Apache-2.0"
			(at 0 0 180)
			(unlocked yes)
			(layer "F.Fab")
			(hide yes)
			(effects
				(font
					(size 1 1)
					(thickness 0.15)
				)
			)
		)
		(property "Author" "Antmicro"
			(at 0 0 180)
			(unlocked yes)
			(layer "F.Fab")
			(hide yes)
			(effects
				(font
					(size 1 1)
					(thickness 0.15)
				)
			)
		)
		(property "Voltage" "50V"
			(at 0 0 180)
			(unlocked yes)
			(layer "F.Fab")
			(hide yes)
			(effects
				(font
					(size 1 1)
					(thickness 0.15)
				)
			)
		)
		(property "Dielectric" "X5R"
			(at 0 0 180)
			(unlocked yes)
			(layer "F.Fab")
			(hide yes)
			(effects
				(font
					(size 1 1)
					(thickness 0.15)
				)
			)
		)
		(sheetname "/USB Hub/")
		(sheetfile "usb_hub.kicad_sch")
		(attr smd)
		(fp_rect
			(start -0.925 -0.47)
			(end 0.925 0.47)
			(stroke
				(width 0.05)
				(type default)
			)
			(fill no)
			(layer "F.CrtYd")
		)
		(fp_line
			(start 0.504 0.248)
			(end -0.494 0.248)
			(stroke
				(width 0.15)
				(type solid)
			)
			(layer "F.Fab")
		)
		(fp_line
			(start 0.504 -0.25)
			(end 0.504 0.248)
			(stroke
				(width 0.15)
				(type solid)
			)
			(layer "F.Fab")
		)
		(fp_line
			(start -0.494 0.248)
			(end -0.494 -0.25)
			(stroke
				(width 0.15)
				(type solid)
			)
			(layer "F.Fab")
		)
		(fp_line
			(start -0.494 -0.25)
			(end 0.504 -0.25)
			(stroke
				(width 0.15)
				(type solid)
			)
			(layer "F.Fab")
		)
		(fp_text user "Author: Antmicro"
			(at -0.939 3.399 0)
			(layer "F.Fab")
			(effects
				(font
					(size 0.7 0.7)
					(thickness 0.15)
				)
				(justify right top)
			)
		)
		(fp_text user "${REFERENCE}"
			(at -0.939 4.599 0)
			(layer "F.Fab")
			(effects
				(font
					(size 0.7 0.7)
					(thickness 0.15)
				)
				(justify right top)
			)
		)
		(fp_text user "License: Apache-2.0"
			(at -0.939 5.799 0)
			(layer "F.Fab")
			(effects
				(font
					(size 0.7 0.7)
					(thickness 0.15)
				)
				(justify right top)
			)
		)
		(pad "1" smd roundrect
			(at -0.48 0 180)
			(size 0.59 0.64)
			(layers "F.Cu" "F.Mask" "F.Paste")
			(roundrect_rratio 0.25)
			(net 110 "/USB Hub/USBC4_CONN_TX2_N")
			(pintype "passive")
		)
		(pad "2" smd roundrect
			(at 0.48 0 180)
			(size 0.59 0.64)
			(layers "F.Cu" "F.Mask" "F.Paste")
			(roundrect_rratio 0.25)
			(net 214 "/USB Hub/USBC4_TX_{2}-")
			(pintype "passive")
		)
	)
	(footprint "antmicro-footprints:C_0402_1005Metric"
		(layer "F.Cu")
		(at 152.48 116.1 180)
		(descr "Capacitor SMD 0402")
		(tags "capacitor SMD 0402")
		(property "Reference" "C1"
			(at -2.52 1.7 0)
			(layer "F.SilkS")
			(effects
				(font
					(size 0.7 0.7)
					(thickness 0.15)
				)
				(justify right top)
			)
		)
		(property "Value" "C_100n_0402"
			(at -1.022927 2.155213 0)
			(layer "F.Fab")
			(effects
				(font
					(size 0.7 0.7)
					(thickness 0.15)
				)
				(justify right top)
			)
		)
		(property "Datasheet" "https://www.murata.com/products/productdetail?partno=GRM155R61H104KE14%23"
			(at 0 0 0)
			(layer "F.Fab")
			(hide yes)
			(effects
				(font
					(size 1.27 1.27)
					(thickness 0.15)
				)
			)
		)
		(property "Description" "SMD Multilayer Ceramic Capacitor, 0.1 µF, 50 V, 0402 [1005 Metric], ± 10%, X5R, GRM Series"
			(at 0 0 0)
			(layer "F.Fab")
			(hide yes)
			(effects
				(font
					(size 1.27 1.27)
					(thickness 0.15)
				)
			)
		)
		(property "Manufacturer" "Murata"
			(at 0 0 180)
			(unlocked yes)
			(layer "F.Fab")
			(hide yes)
			(effects
				(font
					(size 1 1)
					(thickness 0.15)
				)
			)
		)
		(property "MPN" "GRM155R61H104KE14D"
			(at 0 0 180)
			(unlocked yes)
			(layer "F.Fab")
			(hide yes)
			(effects
				(font
					(size 1 1)
					(thickness 0.15)
				)
			)
		)
		(property "Val" "100n"
			(at 0 0 180)
			(unlocked yes)
			(layer "F.Fab")
			(hide yes)
			(effects
				(font
					(size 1 1)
					(thickness 0.15)
				)
			)
		)
		(property "License" "Apache-2.0"
			(at 0 0 180)
			(unlocked yes)
			(layer "F.Fab")
			(hide yes)
			(effects
				(font
					(size 1 1)
					(thickness 0.15)
				)
			)
		)
		(property "Author" "Antmicro"
			(at 0 0 180)
			(unlocked yes)
			(layer "F.Fab")
			(hide yes)
			(effects
				(font
					(size 1 1)
					(thickness 0.15)
				)
			)
		)
		(property "Voltage" "50V"
			(at 0 0 180)
			(unlocked yes)
			(layer "F.Fab")
			(hide yes)
			(effects
				(font
					(size 1 1)
					(thickness 0.15)
				)
			)
		)
		(property "Dielectric" "X5R"
			(at 0 0 180)
			(unlocked yes)
			(layer "F.Fab")
			(hide yes)
			(effects
				(font
					(size 1 1)
					(thickness 0.15)
				)
			)
		)
		(sheetname "/SoM_IO/")
		(sheetfile "som_io.kicad_sch")
		(attr smd)
		(fp_poly
			(pts
				(xy -0.925 -0.47) (xy -0.925 0.47) (xy 0.925 0.47) (xy 0.925 -0.47)
			)
			(stroke
				(width 0.05)
				(type default)
			)
			(fill no)
			(layer "F.CrtYd")
		)
		(fp_line
			(start 0.504 0.248)
			(end -0.494 0.248)
			(stroke
				(width 0.15)
				(type solid)
			)
			(layer "F.Fab")
		)
		(fp_line
			(start 0.504 -0.25)
			(end 0.504 0.248)
			(stroke
				(width 0.15)
				(type solid)
			)
			(layer "F.Fab")
		)
		(fp_line
			(start -0.494 0.248)
			(end -0.494 -0.25)
			(stroke
				(width 0.15)
				(type solid)
			)
			(layer "F.Fab")
		)
		(fp_line
			(start -0.494 -0.25)
			(end 0.504 -0.25)
			(stroke
				(width 0.15)
				(type solid)
			)
			(layer "F.Fab")
		)
		(fp_text user "Author: Antmicro"
			(at -0.939 3.399 0)
			(layer "F.Fab")
			(effects
				(font
					(size 0.7 0.7)
					(thickness 0.15)
				)
				(justify right top)
			)
		)
		(fp_text user "${REFERENCE}"
			(at -0.939 4.599 0)
			(layer "F.Fab")
			(effects
				(font
					(size 0.7 0.7)
					(thickness 0.15)
				)
				(justify right top)
			)
		)
		(fp_text user "License: Apache-2.0"
			(at -0.939 5.799 0)
			(layer "F.Fab")
			(effects
				(font
					(size 0.7 0.7)
					(thickness 0.15)
				)
				(justify right top)
			)
		)
		(pad "1" smd roundrect
			(at -0.48 0 180)
			(size 0.59 0.64)
			(layers "F.Cu" "F.Mask" "F.Paste")
			(roundrect_rratio 0.25)
			(net 1 "GND")
			(pintype "passive")
		)
		(pad "2" smd roundrect
			(at 0.48 0 180)
			(size 0.59 0.64)
			(layers "F.Cu" "F.Mask" "F.Paste")
			(roundrect_rratio 0.25)
			(net 11 "+1V8")
			(pintype "passive")
		)
	)
	(footprint "antmicro-footprints:C_0402_1005Metric"
		(layer "F.Cu")
		(at 201.7 133.7 90)
		(descr "Capacitor SMD 0402")
		(tags "capacitor SMD 0402")
		(property "Reference" "C96"
			(at -1.1 -1.8 90)
			(layer "F.SilkS")
			(effects
				(font
					(size 0.7 0.7)
					(thickness 0.15)
				)
				(justify left bottom)
			)
		)
		(property "Value" "C_100n_0402"
			(at -1.022927 2.155213 90)
			(layer "F.Fab")
			(effects
				(font
					(size 0.7 0.7)
					(thickness 0.15)
				)
				(justify left bottom)
			)
		)
		(property "Datasheet" "https://www.murata.com/products/productdetail?partno=GRM155R61H104KE14%23"
			(at 0 0 90)
			(layer "F.Fab")
			(hide yes)
			(effects
				(font
					(size 1.27 1.27)
					(thickness 0.15)
				)
			)
		)
		(property "Description" "SMD Multilayer Ceramic Capacitor, 0.1 µF, 50 V, 0402 [1005 Metric], ± 10%, X5R, GRM Series"
			(at 0 0 90)
			(layer "F.Fab")
			(hide yes)
			(effects
				(font
					(size 1.27 1.27)
					(thickness 0.15)
				)
			)
		)
		(property "MPN" "GRM155R61H104KE14D"
			(at 0 0 90)
			(unlocked yes)
			(layer "F.Fab")
			(hide yes)
			(effects
				(font
					(size 1 1)
					(thickness 0.15)
				)
			)
		)
		(property "Val" "100n"
			(at 0 0 90)
			(unlocked yes)
			(layer "F.Fab")
			(hide yes)
			(effects
				(font
					(size 1 1)
					(thickness 0.15)
				)
			)
		)
		(property "Voltage" "50V"
			(at 0 0 90)
			(unlocked yes)
			(layer "F.Fab")
			(hide yes)
			(effects
				(font
					(size 1 1)
					(thickness 0.15)
				)
			)
		)
		(property "Dielectric" "X5R"
			(at 0 0 90)
			(unlocked yes)
			(layer "F.Fab")
			(hide yes)
			(effects
				(font
					(size 1 1)
					(thickness 0.15)
				)
			)
		)
		(property "Manufacturer" "Murata"
			(at 0 0 90)
			(unlocked yes)
			(layer "F.Fab")
			(hide yes)
			(effects
				(font
					(size 1 1)
					(thickness 0.15)
				)
			)
		)
		(property "License" "Apache-2.0"
			(at 0 0 90)
			(unlocked yes)
			(layer "F.Fab")
			(hide yes)
			(effects
				(font
					(size 1 1)
					(thickness 0.15)
				)
			)
		)
		(property "Author" "Antmicro"
			(at 0 0 90)
			(unlocked yes)
			(layer "F.Fab")
			(hide yes)
			(effects
				(font
					(size 1 1)
					(thickness 0.15)
				)
			)
		)
		(sheetname "/USB Hub/")
		(sheetfile "usb_hub.kicad_sch")
		(attr smd)
		(fp_rect
			(start -0.925 -0.47)
			(end 0.925 0.47)
			(stroke
				(width 0.05)
				(type default)
			)
			(fill no)
			(layer "F.CrtYd")
		)
		(fp_line
			(start 0.504 -0.25)
			(end 0.504 0.248)
			(stroke
				(width 0.15)
				(type solid)
			)
			(layer "F.Fab")
		)
		(fp_line
			(start -0.494 -0.25)
			(end 0.504 -0.25)
			(stroke
				(width 0.15)
				(type solid)
			)
			(layer "F.Fab")
		)
		(fp_line
			(start 0.504 0.248)
			(end -0.494 0.248)
			(stroke
				(width 0.15)
				(type solid)
			)
			(layer "F.Fab")
		)
		(fp_line
			(start -0.494 0.248)
			(end -0.494 -0.25)
			(stroke
				(width 0.15)
				(type solid)
			)
			(layer "F.Fab")
		)
		(fp_text user "${REFERENCE}"
			(at -0.939 4.599 90)
			(layer "F.Fab")
			(effects
				(font
					(size 0.7 0.7)
					(thickness 0.15)
				)
				(justify left bottom)
			)
		)
		(fp_text user "Author: Antmicro"
			(at -0.939 3.399 90)
			(layer "F.Fab")
			(effects
				(font
					(size 0.7 0.7)
					(thickness 0.15)
				)
				(justify left bottom)
			)
		)
		(fp_text user "License: Apache-2.0"
			(at -0.939 5.799 90)
			(layer "F.Fab")
			(effects
				(font
					(size 0.7 0.7)
					(thickness 0.15)
				)
				(justify left bottom)
			)
		)
		(pad "1" smd roundrect
			(at -0.48 0 90)
			(size 0.59 0.64)
			(layers "F.Cu" "F.Mask" "F.Paste")
			(roundrect_rratio 0.25)
			(net 1 "GND")
			(pintype "passive")
		)
		(pad "2" smd roundrect
			(at 0.48 0 90)
			(size 0.59 0.64)
			(layers "F.Cu" "F.Mask" "F.Paste")
			(roundrect_rratio 0.25)
			(net 2 "+3V3")
			(pintype "passive")
		)
	)
	(footprint "antmicro-footprints:R_0402_1005Metric"
		(layer "F.Cu")
		(at 183.754468 88.785 90)
		(descr "Resistor SMD 0402")
		(tags "resistor SMD 0402")
		(property "Reference" "R70"
			(at -1.03 2.61 90)
			(layer "F.SilkS")
			(effects
				(font
					(size 0.7 0.7)
					(thickness 0.15)
				)
				(justify left bottom)
			)
		)
		(property "Value" "R_10k_0402"
			(at -1.011843 1.772047 90)
			(layer "F.Fab")
			(effects
				(font
					(size 0.7 0.7)
					(thickness 0.15)
				)
				(justify left bottom)
			)
		)
		(property "Datasheet" "https://www.bourns.com/docs/product-datasheets/cr.pdf"
			(at 0 0 90)
			(layer "F.Fab")
			(hide yes)
			(effects
				(font
					(size 1.27 1.27)
					(thickness 0.15)
				)
			)
		)
		(property "Description" "SMD Chip Resistor, 10 kohm, ± 1%, 62.5 mW, 0402 [1005 Metric], Thick Film, General Purpose"
			(at 0 0 90)
			(layer "F.Fab")
			(hide yes)
			(effects
				(font
					(size 1.27 1.27)
					(thickness 0.15)
				)
			)
		)
		(property "MPN" "CR0402-FX-1002GLF"
			(at 0 0 90)
			(unlocked yes)
			(layer "F.Fab")
			(hide yes)
			(effects
				(font
					(size 1 1)
					(thickness 0.15)
				)
			)
		)
		(property "Manufacturer" "Bourns"
			(at 0 0 90)
			(unlocked yes)
			(layer "F.Fab")
			(hide yes)
			(effects
				(font
					(size 1 1)
					(thickness 0.15)
				)
			)
		)
		(property "License" "Apache-2.0"
			(at 0 0 90)
			(unlocked yes)
			(layer "F.Fab")
			(hide yes)
			(effects
				(font
					(size 1 1)
					(thickness 0.15)
				)
			)
		)
		(property "Author" "Antmicro"
			(at 0 0 90)
			(unlocked yes)
			(layer "F.Fab")
			(hide yes)
			(effects
				(font
					(size 1 1)
					(thickness 0.15)
				)
			)
		)
		(property "Val" "10k"
			(at 0 0 90)
			(unlocked yes)
			(layer "F.Fab")
			(hide yes)
			(effects
				(font
					(size 1 1)
					(thickness 0.15)
				)
			)
		)
		(property "Tolerance" "1%"
			(at 0 0 90)
			(unlocked yes)
			(layer "F.Fab")
			(hide yes)
			(effects
				(font
					(size 1 1)
					(thickness 0.15)
				)
			)
		)
		(component_classes
			(class "DCDC_SOM")
		)
		(sheetname "/DCDC/")
		(sheetfile "dcdc.kicad_sch")
		(attr smd)
		(fp_rect
			(start -0.925 -0.47)
			(end 0.925 0.47)
			(stroke
				(width 0.05)
				(type default)
			)
			(fill no)
			(layer "F.CrtYd")
		)
		(fp_rect
			(start -0.5 -0.25)
			(end 0.5 0.25)
			(stroke
				(width 0.15)
				(type solid)
			)
			(fill no)
			(layer "F.Fab")
		)
		(fp_text user "License: Apache-2.0"
			(at -0.95 5.169 90)
			(layer "F.Fab")
			(effects
				(font
					(size 0.7 0.7)
					(thickness 0.15)
				)
				(justify left bottom)
			)
		)
		(fp_text user "${REFERENCE}"
			(at -0.95 3.168 90)
			(layer "F.Fab")
			(effects
				(font
					(size 0.7 0.7)
					(thickness 0.15)
				)
				(justify left bottom)
			)
		)
		(fp_text user "Author: Antmicro"
			(at -0.95 4.169 90)
			(layer "F.Fab")
			(effects
				(font
					(size 0.7 0.7)
					(thickness 0.15)
				)
				(justify left bottom)
			)
		)
		(pad "1" smd roundrect
			(at -0.48 0 90)
			(size 0.59 0.64)
			(layers "F.Cu" "F.Mask" "F.Paste")
			(roundrect_rratio 0.25)
			(net 1 "GND")
			(pintype "passive")
		)
		(pad "2" smd roundrect
			(at 0.48 0 90)
			(size 0.59 0.64)
			(layers "F.Cu" "F.Mask" "F.Paste")
			(roundrect_rratio 0.25)
			(net 1219 "/DCDC/16V_FB")
			(pintype "passive")
		)
	)
)
